(kicad_pcb
	(version 20260206)
	(generator "pcbnew")
	(generator_version "10.0")
	(general
		(thickness 1.6)
		(legacy_teardrops no)
	)
	(paper "A4")
	(title_block
		(title "v1-chassis-manager — T6M_CM_d_v01_1031_1645.brd")
		(comment 1 "Open CloudServer (Microsoft) / footprints 1438-1446 of 2512")
	)
	(layers
		(0 "F.Cu" signal "TOP")
		(4 "In1.Cu" signal "GND1")
		(6 "In2.Cu" signal "IN1")
		(8 "In3.Cu" signal "VCC1")
		(10 "In4.Cu" signal "VCC2")
		(12 "In5.Cu" signal "GND2")
		(14 "In6.Cu" signal "IN2")
		(16 "In7.Cu" signal "IN3")
		(18 "In8.Cu" signal "GND3")
		(2 "B.Cu" signal "BOTTOM")
		(9 "F.Adhes" user "F.Adhesive")
		(11 "B.Adhes" user "B.Adhesive")
		(13 "F.Paste" user "Package Geometry/Pastemask Top")
		(15 "B.Paste" user "Package Geometry/Pastemask Bottom")
		(5 "F.SilkS" user "Ref Des/Silkscreen Top")
		(7 "B.SilkS" user "Ref Des/Silkscreen Bottom")
		(1 "F.Mask" user "Board Geometry/Soldermask Top")
		(3 "B.Mask" user "Board Geometry/Soldermask Bottom")
		(17 "Dwgs.User" user "User.Drawings")
		(19 "Cmts.User" user "User.Comments")
		(21 "Eco1.User" user "User.Eco1")
		(23 "Eco2.User" user "User.Eco2")
		(25 "Edge.Cuts" user "Board Geometry/Outline")
		(27 "Margin" user)
		(31 "F.CrtYd" user "Package Geometry/Place Bound Top")
		(29 "B.CrtYd" user "Package Geometry/Place Bound Bottom")
		(35 "F.Fab" user "Ref Des/Assembly Top")
		(33 "B.Fab" user "Ref Des/Assembly Bottom")
	)
	(footprint ""
		(layer "F.Cu")
		(at 51.67376 -188.126624 90)
		(property "Reference" "R848"
			(at 4.548886 0.205232 90)
			(unlocked yes)
			(layer "F.SilkS")
			(effects
				(font
					(size 0.7874 0.5842)
					(thickness 0.1524)
				)
				(justify left)
			)
		)
		(property "Value" ""
			(at 0 0 90)
			(layer "F.Fab")
			(effects
				(font
					(size 1.27 1.27)
				)
			)
		)
		(duplicate_pad_numbers_are_jumpers no)
		(fp_line
			(start 0.7874 -0.4064)
			(end 0.7874 0.4064)
			(stroke
				(width 0.1524)
				(type default)
			)
			(layer "F.SilkS")
		)
		(fp_line
			(start -0.7874 -0.4064)
			(end 0.7874 -0.4064)
			(stroke
				(width 0.1524)
				(type default)
			)
			(layer "F.SilkS")
		)
		(fp_line
			(start 0.7874 0.4064)
			(end -0.7874 0.4064)
			(stroke
				(width 0.1524)
				(type default)
			)
			(layer "F.SilkS")
		)
		(fp_line
			(start -0.7874 0.4064)
			(end -0.7874 -0.4064)
			(stroke
				(width 0.1524)
				(type default)
			)
			(layer "F.SilkS")
		)
		(fp_poly
			(pts
				(xy -0.508 0.2794) (xy -0.508 0.2286) (xy -0.635 0.2286) (xy -0.635 -0.254) (xy -0.5334 -0.254)
				(xy -0.5334 -0.2794) (xy 0.5334 -0.2794) (xy 0.5334 -0.254) (xy 0.635 -0.254) (xy 0.635 0.254) (xy 0.5334 0.254)
				(xy 0.5334 0.2794)
			)
			(stroke
				(width 0)
				(type default)
			)
			(fill no)
			(layer "F.CrtYd")
		)
		(pad "1" smd rect
			(at 0.40005 0 90)
			(size 0.4572 0.508)
			(layers "F.Cu" "F.Mask" "F.Paste")
			(net "PSU2_AC_OK_R")
		)
		(pad "2" smd rect
			(at -0.40005 0 90)
			(size 0.4572 0.508)
			(layers "F.Cu" "F.Mask" "F.Paste")
			(net "GND")
		)
	)
	(footprint ""
		(layer "F.Cu")
		(at 20.47494 -41.548558 90)
		(property "Reference" "U46"
			(at -2.331974 0.548386 0)
			(unlocked yes)
			(layer "F.SilkS")
			(effects
				(font
					(size 0.7874 0.5842)
					(thickness 0.1524)
				)
			)
		)
		(property "Value" ""
			(at 0 0 90)
			(layer "F.Fab")
			(effects
				(font
					(size 1.27 1.27)
				)
			)
		)
		(duplicate_pad_numbers_are_jumpers no)
		(fp_line
			(start 1.651 -1.905)
			(end 1.651 1.905)
			(stroke
				(width 0.1524)
				(type default)
			)
			(layer "F.SilkS")
		)
		(fp_line
			(start -1.651 -1.905)
			(end 1.651 -1.905)
			(stroke
				(width 0.1524)
				(type default)
			)
			(layer "F.SilkS")
		)
		(fp_line
			(start 1.651 1.905)
			(end -1.651 1.905)
			(stroke
				(width 0.1524)
				(type default)
			)
			(layer "F.SilkS")
		)
		(fp_line
			(start -1.651 1.905)
			(end -1.651 -1.905)
			(stroke
				(width 0.1524)
				(type default)
			)
			(layer "F.SilkS")
		)
		(fp_poly
			(pts
				(xy -1.524 0.7112) (xy -1.524 1.7526) (xy -0.508 1.7526) (xy -0.508 0.6985) (xy 0.508 0.6985) (xy 0.508 1.7526)
				(xy 1.524 1.7526) (xy 1.524 0.6985) (xy 1.524 -0.6985) (xy 0.508 -0.6985) (xy 0.508 -1.7526) (xy -0.508 -1.7526)
				(xy -0.508 -0.6985) (xy -1.524 -0.6985) (xy -1.524 0.6985)
			)
			(stroke
				(width 0)
				(type default)
			)
			(fill no)
			(layer "F.CrtYd")
		)
		(fp_text user "3"
			(at -2.892044 -1.7399 0)
			(unlocked yes)
			(layer "F.SilkS")
			(effects
				(font
					(size 0.635 0.4064)
					(thickness 0.1524)
				)
			)
		)
		(fp_text user "2"
			(at 2.230374 0.85344 0)
			(unlocked yes)
			(layer "F.SilkS")
			(effects
				(font
					(size 0.635 0.4064)
					(thickness 0.1524)
				)
			)
		)
		(fp_text user "1"
			(at -2.13106 2.29616 0)
			(unlocked yes)
			(layer "F.SilkS")
			(effects
				(font
					(size 0.635 0.4064)
					(thickness 0.1524)
				)
			)
		)
		(pad "1" smd rect
			(at -1.016 1.1176 90)
			(size 1.016 1.27)
			(layers "F.Cu" "F.Mask" "F.Paste")
			(net "GND")
		)
		(pad "2" smd rect
			(at 1.016 1.1176 90)
			(size 1.016 1.27)
			(layers "F.Cu" "F.Mask" "F.Paste")
			(net "P5V_CRT")
		)
		(pad "3" smd rect
			(at 0 -1.1176 90)
			(size 1.016 1.27)
			(layers "F.Cu" "F.Mask" "F.Paste")
			(net "CRT_R")
		)
	)
	(footprint ""
		(layer "F.Cu")
		(at 188.214 -125.095)
		(property "Reference" "R1287"
			(at 6.35 18.94967 0)
			(unlocked yes)
			(layer "F.SilkS")
			(effects
				(font
					(size 0.7874 0.5842)
					(thickness 0.1524)
				)
				(justify left)
			)
		)
		(property "Value" ""
			(at 0 0 0)
			(layer "F.Fab")
			(effects
				(font
					(size 1.27 1.27)
				)
			)
		)
		(duplicate_pad_numbers_are_jumpers no)
		(fp_line
			(start -0.7874 -0.4064)
			(end 0.7874 -0.4064)
			(stroke
				(width 0.1524)
				(type default)
			)
			(layer "F.SilkS")
		)
		(fp_line
			(start -0.7874 0.4064)
			(end -0.7874 -0.4064)
			(stroke
				(width 0.1524)
				(type default)
			)
			(layer "F.SilkS")
		)
		(fp_line
			(start 0.7874 -0.4064)
			(end 0.7874 0.4064)
			(stroke
				(width 0.1524)
				(type default)
			)
			(layer "F.SilkS")
		)
		(fp_line
			(start 0.7874 0.4064)
			(end -0.7874 0.4064)
			(stroke
				(width 0.1524)
				(type default)
			)
			(layer "F.SilkS")
		)
		(fp_poly
			(pts
				(xy -0.508 0.2794) (xy -0.508 0.2286) (xy -0.635 0.2286) (xy -0.635 -0.254) (xy -0.5334 -0.254)
				(xy -0.5334 -0.2794) (xy 0.5334 -0.2794) (xy 0.5334 -0.254) (xy 0.635 -0.254) (xy 0.635 0.254) (xy 0.5334 0.254)
				(xy 0.5334 0.2794)
			)
			(stroke
				(width 0)
				(type default)
			)
			(fill no)
			(layer "F.CrtYd")
		)
		(pad "1" smd rect
			(at 0.40005 0)
			(size 0.4572 0.508)
			(layers "F.Cu" "F.Mask" "F.Paste")
			(net "SIO_JTAG_CPLD1_TCK")
		)
		(pad "2" smd rect
			(at -0.40005 0)
			(size 0.4572 0.508)
			(layers "F.Cu" "F.Mask" "F.Paste")
			(net "JTAG_CPLD1_TCK")
		)
	)
	(footprint ""
		(layer "F.Cu")
		(at 112.529112 -138.354308 90)
		(property "Reference" "PC122"
			(at 3.235452 3.561334 90)
			(unlocked yes)
			(layer "F.SilkS")
			(effects
				(font
					(size 0.635 0.4064)
					(thickness 0.1524)
				)
				(justify left)
			)
		)
		(property "Value" ""
			(at 0 0 90)
			(layer "F.Fab")
			(effects
				(font
					(size 1.27 1.27)
				)
			)
		)
		(duplicate_pad_numbers_are_jumpers no)
		(fp_line
			(start 0.7874 -0.4064)
			(end 0.7874 0.4064)
			(stroke
				(width 0.1524)
				(type default)
			)
			(layer "F.SilkS")
		)
		(fp_line
			(start -0.7874 -0.4064)
			(end 0.7874 -0.4064)
			(stroke
				(width 0.1524)
				(type default)
			)
			(layer "F.SilkS")
		)
		(fp_line
			(start 0 0.381)
			(end 0 -0.381)
			(stroke
				(width 0.1524)
				(type default)
			)
			(layer "F.SilkS")
		)
		(fp_line
			(start 0.7874 0.4064)
			(end -0.7874 0.4064)
			(stroke
				(width 0.1524)
				(type default)
			)
			(layer "F.SilkS")
		)
		(fp_line
			(start -0.7874 0.4064)
			(end -0.7874 -0.4064)
			(stroke
				(width 0.1524)
				(type default)
			)
			(layer "F.SilkS")
		)
		(fp_poly
			(pts
				(xy -0.5334 0.254) (xy -0.635 0.254) (xy -0.635 0.2286) (xy -0.635 -0.254) (xy -0.5334 -0.254) (xy -0.5334 -0.2794)
				(xy 0.5334 -0.2794) (xy 0.5334 -0.254) (xy 0.635 -0.254) (xy 0.635 0.254) (xy 0.5334 0.254) (xy 0.5334 0.2794)
				(xy -0.508 0.2794) (xy -0.5334 0.2794)
			)
			(stroke
				(width 0)
				(type default)
			)
			(fill no)
			(layer "F.CrtYd")
		)
		(pad "1" smd rect
			(at 0.40005 0 90)
			(size 0.4572 0.508)
			(layers "F.Cu" "F.Mask" "F.Paste")
			(net "VR_PVCCP_NODE1_EN")
		)
		(pad "2" smd rect
			(at -0.40005 0 90)
			(size 0.4572 0.508)
			(layers "F.Cu" "F.Mask" "F.Paste")
			(net "AGND_PVCCP_NODE1")
		)
	)
	(footprint ""
		(layer "F.Cu")
		(at 94.654878 -155.28163 -90)
		(property "Reference" "PL4"
			(at 4.078224 2.123948 0)
			(unlocked yes)
			(layer "F.SilkS")
			(effects
				(font
					(size 0.7874 0.5842)
					(thickness 0.1524)
				)
				(justify left)
			)
		)
		(property "Value" ""
			(at 0 0 270)
			(layer "F.Fab")
			(effects
				(font
					(size 1.27 1.27)
				)
			)
		)
		(duplicate_pad_numbers_are_jumpers no)
		(fp_line
			(start -3.350006 4.1656)
			(end -3.350006 -4.1656)
			(stroke
				(width 0.1524)
				(type default)
			)
			(layer "F.SilkS")
		)
		(fp_line
			(start 3.350006 4.1656)
			(end -3.350006 4.1656)
			(stroke
				(width 0.1524)
				(type default)
			)
			(layer "F.SilkS")
		)
		(fp_line
			(start -3.350006 -4.1656)
			(end 3.350006 -4.1656)
			(stroke
				(width 0.1524)
				(type default)
			)
			(layer "F.SilkS")
		)
		(fp_line
			(start 3.350006 -4.1656)
			(end 3.350006 4.1656)
			(stroke
				(width 0.1524)
				(type default)
			)
			(layer "F.SilkS")
		)
		(fp_poly
			(pts
				(xy -3.350006 -3.64998) (xy -1.7018 -3.64998) (xy -1.7018 -4.05257) (xy 1.7018 -4.05257) (xy 1.7018 -3.64998)
				(xy 3.350006 -3.64998) (xy 3.350006 3.64998) (xy 1.7018 3.64998) (xy 1.7018 4.05257) (xy -1.7018 4.05257)
				(xy -1.7018 3.64998) (xy -3.350006 3.64998)
			)
			(stroke
				(width 0)
				(type default)
			)
			(fill no)
			(layer "F.CrtYd")
		)
		(fp_line
			(start -3.350006 3.64998)
			(end -3.350006 -3.64998)
			(stroke
				(width 0.1)
				(type default)
			)
			(layer "F.Fab")
		)
		(fp_line
			(start 3.350006 3.64998)
			(end -3.350006 3.64998)
			(stroke
				(width 0.1)
				(type default)
			)
			(layer "F.Fab")
		)
		(fp_line
			(start -3.350006 -3.64998)
			(end 3.350006 -3.64998)
			(stroke
				(width 0.1)
				(type default)
			)
			(layer "F.Fab")
		)
		(fp_line
			(start 3.350006 -3.64998)
			(end 3.350006 3.64998)
			(stroke
				(width 0.1)
				(type default)
			)
			(layer "F.Fab")
		)
		(pad "1" smd rect
			(at 0 -2.92481 180)
			(size 2.15392 3.302)
			(layers "F.Cu" "F.Mask" "F.Paste")
			(net "SW_P1V8_STB_NODE1_PH")
		)
		(pad "2" smd rect
			(at 0 2.92481 180)
			(size 2.15392 3.302)
			(layers "F.Cu" "F.Mask" "F.Paste")
			(net "P1V8_STB_NODE1")
		)
	)
	(footprint ""
		(layer "F.Cu")
		(at 169.622724 -57.47258 90)
		(property "Reference" "L44"
			(at -0.940562 -7.028434 90)
			(unlocked yes)
			(layer "F.SilkS")
			(effects
				(font
					(size 0.7874 0.5842)
					(thickness 0.1524)
				)
				(justify left)
			)
		)
		(property "Value" ""
			(at 0 0 90)
			(layer "F.Fab")
			(effects
				(font
					(size 1.27 1.27)
				)
			)
		)
		(duplicate_pad_numbers_are_jumpers no)
		(fp_line
			(start 0.989838 -2.0066)
			(end 0.989838 2.0066)
			(stroke
				(width 0.1524)
				(type default)
			)
			(layer "F.SilkS")
		)
		(fp_line
			(start -1.015238 -2.0066)
			(end 0.989838 -2.0066)
			(stroke
				(width 0.1524)
				(type default)
			)
			(layer "F.SilkS")
		)
		(fp_line
			(start 0.989838 2.0066)
			(end -1.015238 2.0066)
			(stroke
				(width 0.1524)
				(type default)
			)
			(layer "F.SilkS")
		)
		(fp_line
			(start -1.015238 2.0066)
			(end -1.015238 -2.0066)
			(stroke
				(width 0.1524)
				(type default)
			)
			(layer "F.SilkS")
		)
		(fp_poly
			(pts
				(xy -0.899922 -1.700022) (xy -0.899922 1.700022) (xy -0.8636 1.700022) (xy -0.8636 1.9304) (xy -0.127 1.9304)
				(xy -0.127 1.700022) (xy 0.127 1.700022) (xy 0.127 1.9304) (xy 0.8636 1.9304) (xy 0.8636 1.700022)
				(xy 0.899922 1.700022) (xy 0.899922 -1.700022) (xy 0.8636 -1.700022) (xy 0.8636 -1.9304) (xy 0.127 -1.9304)
				(xy 0.127 -1.700022) (xy -0.127 -1.700022) (xy -0.127 -1.9304) (xy -0.8636 -1.9304) (xy -0.8636 -1.700022)
			)
			(stroke
				(width 0)
				(type default)
			)
			(fill no)
			(layer "F.CrtYd")
		)
		(fp_line
			(start 0.899922 -1.700022)
			(end 0.899922 1.700022)
			(stroke
				(width 0.1)
				(type default)
			)
			(layer "F.Fab")
		)
		(fp_line
			(start -0.899922 -1.700022)
			(end 0.899922 -1.700022)
			(stroke
				(width 0.1)
				(type default)
			)
			(layer "F.Fab")
		)
		(fp_line
			(start 0.899922 1.700022)
			(end -0.899922 1.700022)
			(stroke
				(width 0.1)
				(type default)
			)
			(layer "F.Fab")
		)
		(fp_line
			(start -0.899922 1.700022)
			(end -0.899922 -1.700022)
			(stroke
				(width 0.1)
				(type default)
			)
			(layer "F.Fab")
		)
		(pad "1" smd rect
			(at -0.499872 -1.400048 90)
			(size 0.6096 0.9144)
			(layers "F.Cu" "F.Mask" "F.Paste")
			(net "USB2_DN")
		)
		(pad "2" smd rect
			(at -0.499872 1.400048 90)
			(size 0.6096 0.9144)
			(layers "F.Cu" "F.Mask" "F.Paste")
			(net "USB2_L_DN")
		)
		(pad "3" smd rect
			(at 0.499872 1.400048 90)
			(size 0.6096 0.9144)
			(layers "F.Cu" "F.Mask" "F.Paste")
			(net "USB2_L_DP")
		)
		(pad "4" smd rect
			(at 0.499872 -1.400048 90)
			(size 0.6096 0.9144)
			(layers "F.Cu" "F.Mask" "F.Paste")
			(net "USB2_DP")
		)
	)
	(footprint ""
		(layer "F.Cu")
		(at 103.725726 -118.600982 90)
		(property "Reference" "PR56"
			(at 0.012192 -3.62077 0)
			(unlocked yes)
			(layer "F.SilkS")
			(effects
				(font
					(size 0.7874 0.5842)
					(thickness 0.1524)
				)
				(justify left)
			)
		)
		(property "Value" ""
			(at 0 0 90)
			(layer "F.Fab")
			(effects
				(font
					(size 1.27 1.27)
				)
			)
		)
		(duplicate_pad_numbers_are_jumpers no)
		(fp_line
			(start 0.4572 -0.44069)
			(end 0.4572 1.54051)
			(stroke
				(width 0.1524)
				(type default)
			)
			(layer "F.SilkS")
		)
		(fp_line
			(start -0.4572 -0.44069)
			(end 0.4572 -0.44069)
			(stroke
				(width 0.1524)
				(type default)
			)
			(layer "F.SilkS")
		)
		(fp_line
			(start -0.4572 1.51511)
			(end -0.4572 -0.44069)
			(stroke
				(width 0.1524)
				(type default)
			)
			(layer "F.SilkS")
		)
		(fp_line
			(start 0.4572 1.54051)
			(end -0.4572 1.54051)
			(stroke
				(width 0.1524)
				(type default)
			)
			(layer "F.SilkS")
		)
		(fp_line
			(start -0.4572 1.54051)
			(end -0.4572 1.51511)
			(stroke
				(width 0.1524)
				(type default)
			)
			(layer "F.SilkS")
		)
		(fp_poly
			(pts
				(xy 0.3556 0.37211) (xy 0.3556 -0.36449) (xy -0.3556 -0.36449) (xy -0.3556 1.46431) (xy 0.3556 1.46431)
				(xy 0.3556 0.72771)
			)
			(stroke
				(width 0)
				(type default)
			)
			(fill no)
			(layer "F.CrtYd")
		)
		(fp_line
			(start 0.299974 -0.025146)
			(end 0.299974 1.124966)
			(stroke
				(width 0.1)
				(type default)
			)
			(layer "F.Fab")
		)
		(fp_line
			(start -0.299974 -0.025146)
			(end 0.299974 -0.025146)
			(stroke
				(width 0.1)
				(type default)
			)
			(layer "F.Fab")
		)
		(fp_line
			(start 0.299974 1.124966)
			(end -0.299974 1.124966)
			(stroke
				(width 0.1)
				(type default)
			)
			(layer "F.Fab")
		)
		(fp_line
			(start -0.299974 1.124966)
			(end -0.299974 -0.025146)
			(stroke
				(width 0.1)
				(type default)
			)
			(layer "F.Fab")
		)
		(pad "1" smd rect
			(at 0 0 180)
			(size 0.6096 0.6096)
			(layers "F.Cu" "F.Mask" "F.Paste")
			(net "VR_PVCCP_NODE1_ISEN1P_RR")
		)
		(pad "2" smd rect
			(at 0 1.09982 180)
			(size 0.6096 0.6096)
			(layers "F.Cu" "F.Mask" "F.Paste")
			(net "ISENSE_PVCCP_NODE1_ISEN1N")
		)
	)
	(footprint ""
		(layer "F.Cu")
		(at 135.01878 -181.55158 -90)
		(property "Reference" "R1160"
			(at 1.183386 1.493266 90)
			(unlocked yes)
			(layer "F.SilkS")
			(effects
				(font
					(size 0.7874 0.5842)
					(thickness 0.1524)
				)
				(justify left)
			)
		)
		(property "Value" ""
			(at 0 0 270)
			(layer "F.Fab")
			(effects
				(font
					(size 1.27 1.27)
				)
			)
		)
		(duplicate_pad_numbers_are_jumpers no)
		(fp_line
			(start -0.7874 0.4064)
			(end -0.7874 -0.4064)
			(stroke
				(width 0.1524)
				(type default)
			)
			(layer "F.SilkS")
		)
		(fp_line
			(start 0.7874 0.4064)
			(end -0.7874 0.4064)
			(stroke
				(width 0.1524)
				(type default)
			)
			(layer "F.SilkS")
		)
		(fp_line
			(start -0.7874 -0.4064)
			(end 0.7874 -0.4064)
			(stroke
				(width 0.1524)
				(type default)
			)
			(layer "F.SilkS")
		)
		(fp_line
			(start 0.7874 -0.4064)
			(end 0.7874 0.4064)
			(stroke
				(width 0.1524)
				(type default)
			)
			(layer "F.SilkS")
		)
		(fp_poly
			(pts
				(xy -0.508 0.2794) (xy -0.508 0.2286) (xy -0.635 0.2286) (xy -0.635 -0.254) (xy -0.5334 -0.254)
				(xy -0.5334 -0.2794) (xy 0.5334 -0.2794) (xy 0.5334 -0.254) (xy 0.635 -0.254) (xy 0.635 0.254) (xy 0.5334 0.254)
				(xy 0.5334 0.2794)
			)
			(stroke
				(width 0)
				(type default)
			)
			(fill no)
			(layer "F.CrtYd")
		)
		(pad "1" smd rect
			(at 0.40005 0 270)
			(size 0.4572 0.508)
			(layers "F.Cu" "F.Mask" "F.Paste")
			(net "UART_TX_P3")
		)
		(pad "2" smd rect
			(at -0.40005 0 270)
			(size 0.4572 0.508)
			(layers "F.Cu" "F.Mask" "F.Paste")
			(net "GND")
		)
	)
	(footprint ""
		(layer "F.Cu")
		(at 144.764252 -148.21535)
		(property "Reference" "R307"
			(at -0.294386 17.484344 0)
			(unlocked yes)
			(layer "F.SilkS")
			(effects
				(font
					(size 0.7874 0.5842)
					(thickness 0.1524)
				)
				(justify left)
			)
		)
		(property "Value" ""
			(at 0 0 0)
			(layer "F.Fab")
			(effects
				(font
					(size 1.27 1.27)
				)
			)
		)
		(duplicate_pad_numbers_are_jumpers no)
		(fp_line
			(start -0.7874 -0.4064)
			(end 0.7874 -0.4064)
			(stroke
				(width 0.1524)
				(type default)
			)
			(layer "F.SilkS")
		)
		(fp_line
			(start -0.7874 0.4064)
			(end -0.7874 -0.4064)
			(stroke
				(width 0.1524)
				(type default)
			)
			(layer "F.SilkS")
		)
		(fp_line
			(start 0.7874 -0.4064)
			(end 0.7874 0.4064)
			(stroke
				(width 0.1524)
				(type default)
			)
			(layer "F.SilkS")
		)
		(fp_line
			(start 0.7874 0.4064)
			(end -0.7874 0.4064)
			(stroke
				(width 0.1524)
				(type default)
			)
			(layer "F.SilkS")
		)
		(fp_poly
			(pts
				(xy -0.508 0.2794) (xy -0.508 0.2286) (xy -0.635 0.2286) (xy -0.635 -0.254) (xy -0.5334 -0.254)
				(xy -0.5334 -0.2794) (xy 0.5334 -0.2794) (xy 0.5334 -0.254) (xy 0.635 -0.254) (xy 0.635 0.254) (xy 0.5334 0.254)
				(xy 0.5334 0.2794)
			)
			(stroke
				(width 0)
				(type default)
			)
			(fill no)
			(layer "F.CrtYd")
		)
		(pad "1" smd rect
			(at 0.40005 0)
			(size 0.4572 0.508)
			(layers "F.Cu" "F.Mask" "F.Paste")
			(net "GND")
		)
		(pad "2" smd rect
			(at -0.40005 0)
			(size 0.4572 0.508)
			(layers "F.Cu" "F.Mask" "F.Paste")
			(net "PCIE_SW_GPIO7")
		)
	)
)
